(kicad_pcb
	(version 20260206)
	(generator "pcbnew")
	(generator_version "10.0")
	(general
		(thickness 1.6)
		(legacy_teardrops no)
	)
	(paper "A4")
	(title_block
		(title "baseboard — 13948-1b.1110WZS1818.brd")
		(comment 1 "Honey Badger (Wiwynn) / footprints 1683-1688 of 2523")
	)
	(layers
		(0 "F.Cu" signal "TOP")
		(4 "In1.Cu" signal "L2GND")
		(6 "In2.Cu" signal "L3")
		(8 "In3.Cu" signal "L4VCC")
		(10 "In4.Cu" signal "L5VCC")
		(12 "In5.Cu" signal "L6")
		(14 "In6.Cu" signal "L7GND")
		(2 "B.Cu" signal "BOTTOM")
		(9 "F.Adhes" user "F.Adhesive")
		(11 "B.Adhes" user "B.Adhesive")
		(13 "F.Paste" user "Package Geometry/Pastemask Top")
		(15 "B.Paste" user "Package Geometry/Pastemask Bottom")
		(5 "F.SilkS" user "Ref Des/Silkscreen Top")
		(7 "B.SilkS" user "Ref Des/Silkscreen Bottom")
		(1 "F.Mask" user "Board Geometry/Soldermask Top")
		(3 "B.Mask" user "Board Geometry/Soldermask Bottom")
		(17 "Dwgs.User" user "User.Drawings")
		(19 "Cmts.User" user "User.Comments")
		(21 "Eco1.User" user "User.Eco1")
		(23 "Eco2.User" user "User.Eco2")
		(25 "Edge.Cuts" user "Board Geometry/Outline")
		(27 "Margin" user)
		(31 "F.CrtYd" user "Package Geometry/Place Bound Top")
		(29 "B.CrtYd" user "Package Geometry/Place Bound Bottom")
		(35 "F.Fab" user "Ref Des/Assembly Top")
		(33 "B.Fab" user "Ref Des/Assembly Bottom")
	)
	(footprint ""
		(layer "F.Cu")
		(at 192.151 -222.123 90)
		(property "Reference" "R1586"
			(at 0 0 90)
			(layer "F.SilkS")
			(hide yes)
			(effects
				(font
					(size 1.27 1.27)
				)
			)
		)
		(property "Value" "33R2F-3-GP"
			(at 0.064008 -3.993896 90)
			(unlocked yes)
			(layer "F.Fab")
			(hide yes)
			(effects
				(font
					(size 1.016 1.016)
					(thickness 0.1524)
				)
			)
		)
		(property "Device Type" "R402H16"
			(at 0.064008 -5.517896 90)
			(unlocked yes)
			(layer "F.Fab")
			(hide yes)
			(effects
				(font
					(size 1.016 1.016)
					(thickness 0.1524)
				)
			)
		)
		(duplicate_pad_numbers_are_jumpers no)
		(fp_line
			(start 0.508 -0.9398)
			(end -0.508 -0.9398)
			(stroke
				(width 0.1524)
				(type default)
			)
			(layer "F.SilkS")
		)
		(fp_line
			(start -0.508 -0.9398)
			(end -0.508 0.9398)
			(stroke
				(width 0.1524)
				(type default)
			)
			(layer "F.SilkS")
		)
		(fp_rect
			(start -0.508 0.9398)
			(end 0.508 -0.9398)
			(stroke
				(width 0)
				(type default)
			)
			(fill no)
			(layer "F.CrtYd")
		)
		(fp_rect
			(start -0.508 0.9398)
			(end 0.508 -0.9398)
			(stroke
				(width 0)
				(type default)
			)
			(fill no)
			(layer "F.Fab")
		)
		(pad "1" smd custom
			(at 0 -0.4445 90)
			(size 0.1397 0.1397)
			(layers "F.Cu" "F.Mask" "F.Paste")
			(net "FP_RETBTN")
			(options
				(clearance outline)
				(anchor circle)
			)
			(primitives
				(gr_poly
					(pts
						(arc
							(start -0.1778 -0.2794)
							(mid -0.249642 -0.249642)
							(end -0.2794 -0.1778)
						)
						(arc
							(start -0.2794 0.1778)
							(mid -0.249642 0.249642)
							(end -0.1778 0.2794)
						)
						(arc
							(start 0.1778 0.2794)
							(mid 0.249642 0.249642)
							(end 0.2794 0.1778)
						)
						(arc
							(start 0.2794 -0.1778)
							(mid 0.249642 -0.249642)
							(end 0.1778 -0.2794)
						)
					)
					(width 0)
					(fill yes)
				)
			)
		)
		(pad "2" smd custom
			(at 0 0.4445 90)
			(size 0.1397 0.1397)
			(layers "F.Cu" "F.Mask" "F.Paste")
			(net "FP_RETBTN_R")
			(options
				(clearance outline)
				(anchor circle)
			)
			(primitives
				(gr_poly
					(pts
						(arc
							(start -0.1778 -0.2794)
							(mid -0.249642 -0.249642)
							(end -0.2794 -0.1778)
						)
						(arc
							(start -0.2794 0.1778)
							(mid -0.249642 0.249642)
							(end -0.1778 0.2794)
						)
						(arc
							(start 0.1778 0.2794)
							(mid 0.249642 0.249642)
							(end 0.2794 0.1778)
						)
						(arc
							(start 0.2794 -0.1778)
							(mid 0.249642 -0.249642)
							(end 0.1778 -0.2794)
						)
					)
					(width 0)
					(fill yes)
				)
			)
		)
	)
	(footprint ""
		(layer "F.Cu")
		(at 139.45997 -83.566)
		(property "Reference" "R166"
			(at 0 0 0)
			(layer "F.SilkS")
			(hide yes)
			(effects
				(font
					(size 1.27 1.27)
				)
			)
		)
		(property "Value" "4K7R2F-GP"
			(at 0.064008 -3.993896 0)
			(unlocked yes)
			(layer "F.Fab")
			(hide yes)
			(effects
				(font
					(size 1.016 1.016)
					(thickness 0.1524)
				)
			)
		)
		(property "Device Type" "R402H16"
			(at 0.064008 -5.517896 0)
			(unlocked yes)
			(layer "F.Fab")
			(hide yes)
			(effects
				(font
					(size 1.016 1.016)
					(thickness 0.1524)
				)
			)
		)
		(duplicate_pad_numbers_are_jumpers no)
		(fp_line
			(start -0.508 -0.9398)
			(end -0.508 0.9398)
			(stroke
				(width 0.1524)
				(type default)
			)
			(layer "F.SilkS")
		)
		(fp_line
			(start 0.508 -0.9398)
			(end -0.508 -0.9398)
			(stroke
				(width 0.1524)
				(type default)
			)
			(layer "F.SilkS")
		)
		(fp_rect
			(start -0.508 0.9398)
			(end 0.508 -0.9398)
			(stroke
				(width 0)
				(type default)
			)
			(fill no)
			(layer "F.CrtYd")
		)
		(fp_rect
			(start -0.508 0.9398)
			(end 0.508 -0.9398)
			(stroke
				(width 0)
				(type default)
			)
			(fill no)
			(layer "F.Fab")
		)
		(pad "1" smd custom
			(at 0 -0.4445)
			(size 0.1397 0.1397)
			(layers "F.Cu" "F.Mask" "F.Paste")
			(net "TEMP_3_A2")
			(options
				(clearance outline)
				(anchor circle)
			)
			(primitives
				(gr_poly
					(pts
						(arc
							(start -0.1778 -0.2794)
							(mid -0.249642 -0.249642)
							(end -0.2794 -0.1778)
						)
						(arc
							(start -0.2794 0.1778)
							(mid -0.249642 0.249642)
							(end -0.1778 0.2794)
						)
						(arc
							(start 0.1778 0.2794)
							(mid 0.249642 0.249642)
							(end 0.2794 0.1778)
						)
						(arc
							(start 0.2794 -0.1778)
							(mid 0.249642 -0.249642)
							(end 0.1778 -0.2794)
						)
					)
					(width 0)
					(fill yes)
				)
			)
		)
		(pad "2" smd custom
			(at 0 0.4445)
			(size 0.1397 0.1397)
			(layers "F.Cu" "F.Mask" "F.Paste")
			(net "GND")
			(options
				(clearance outline)
				(anchor circle)
			)
			(primitives
				(gr_poly
					(pts
						(arc
							(start -0.1778 -0.2794)
							(mid -0.249642 -0.249642)
							(end -0.2794 -0.1778)
						)
						(arc
							(start -0.2794 0.1778)
							(mid -0.249642 0.249642)
							(end -0.1778 0.2794)
						)
						(arc
							(start 0.1778 0.2794)
							(mid 0.249642 0.249642)
							(end 0.2794 0.1778)
						)
						(arc
							(start 0.2794 -0.1778)
							(mid 0.249642 -0.249642)
							(end 0.1778 -0.2794)
						)
					)
					(width 0)
					(fill yes)
				)
			)
		)
	)
	(footprint ""
		(layer "F.Cu")
		(at 85.579966 -64.897 90)
		(property "Reference" "SX1"
			(at 0 0 90)
			(layer "F.SilkS")
			(hide yes)
			(effects
				(font
					(size 1.27 1.27)
				)
			)
		)
		(property "Value" "XTAL-25MHZ-105-GP"
			(at 0.1016 -10.5918 90)
			(unlocked yes)
			(layer "F.Fab")
			(hide yes)
			(effects
				(font
					(size 1.016 1.016)
					(thickness 0.1524)
				)
			)
		)
		(property "Device Type" "SG8002CAPC-4H40"
			(at 0.1016 -12.6238 90)
			(unlocked yes)
			(layer "F.Fab")
			(hide yes)
			(effects
				(font
					(size 1.016 1.016)
					(thickness 0.1524)
				)
			)
		)
		(duplicate_pad_numbers_are_jumpers no)
		(fp_line
			(start 2.8575 -1.9558)
			(end 2.8575 1.9558)
			(stroke
				(width 0.1524)
				(type default)
			)
			(layer "F.SilkS")
		)
		(fp_line
			(start -2.8575 -1.9558)
			(end 2.8575 -1.9558)
			(stroke
				(width 0.1524)
				(type default)
			)
			(layer "F.SilkS")
		)
		(fp_line
			(start 2.8575 1.9558)
			(end -2.8575 1.9558)
			(stroke
				(width 0.1524)
				(type default)
			)
			(layer "F.SilkS")
		)
		(fp_line
			(start -2.8575 1.9558)
			(end -2.8575 -1.9558)
			(stroke
				(width 0.1524)
				(type default)
			)
			(layer "F.SilkS")
		)
		(fp_poly
			(pts
				(xy -2.3114 2.3876) (xy -1.9558 2.032) (xy -1.6002 2.3876)
			)
			(stroke
				(width 0)
				(type default)
			)
			(fill yes)
			(layer "F.SilkS")
		)
		(fp_rect
			(start -2.99974 2.10058)
			(end 2.99974 -2.09931)
			(stroke
				(width 0)
				(type default)
			)
			(fill no)
			(layer "F.CrtYd")
		)
		(fp_rect
			(start -2.3114 2.3876)
			(end -1.6002 2.10058)
			(stroke
				(width 0)
				(type default)
			)
			(fill no)
			(layer "F.CrtYd")
		)
		(fp_poly
			(pts
				(xy -2.3114 2.3876) (xy -2.3114 2.10058) (xy -2.99974 2.10058) (xy -2.99974 -2.09931) (xy 2.99974 -2.09931)
				(xy 2.99974 2.09931) (xy -1.6002 2.09931) (xy -1.6002 2.3876)
			)
			(stroke
				(width 0)
				(type default)
			)
			(fill no)
			(layer "F.Fab")
		)
		(pad "1" smd rect
			(at -1.8034 1.0414 90)
			(size 1.6002 1.3462)
			(layers "F.Cu" "F.Mask" "F.Paste")
			(net "REF_CLK")
		)
		(pad "2" smd rect
			(at 1.8034 1.0414 90)
			(size 1.6002 1.3462)
			(layers "F.Cu" "F.Mask" "F.Paste")
			(net "GND")
		)
		(pad "3" smd rect
			(at 1.8034 -1.0414 90)
			(size 1.6002 1.3462)
			(layers "F.Cu" "F.Mask" "F.Paste")
			(net "IOC_REF_CLK_P")
		)
		(pad "4" smd rect
			(at -1.8034 -1.0414 90)
			(size 1.6002 1.3462)
			(layers "F.Cu" "F.Mask" "F.Paste")
			(net "GND")
		)
		(zone
			(layer "F.Cu")
			(hatch none 0.5)
			(connect_pads
				(clearance 0)
			)
			(min_thickness 0.25)
			(keepout
				(tracks not_allowed)
				(vias allowed)
				(pads allowed)
				(copperpour not_allowed)
				(footprints allowed)
			)
			(placement
				(enabled no)
				(sheetname "")
			)
			(fill
				(thermal_gap 0.5)
				(thermal_bridge_width 0.5)
				(island_removal_mode 0)
			)
			(polygon
				(pts
					(xy 85.198966 -64.389) (xy 85.198966 -65.405) (xy 85.960966 -65.405) (xy 85.960966 -64.389)
				)
			)
		)
		(zone
			(layer "F.Cu")
			(hatch none 0.5)
			(connect_pads
				(clearance 0)
			)
			(min_thickness 0.25)
			(keepout
				(tracks allowed)
				(vias not_allowed)
				(pads allowed)
				(copperpour not_allowed)
				(footprints allowed)
			)
			(placement
				(enabled no)
				(sheetname "")
			)
			(fill
				(thermal_gap 0.5)
				(thermal_bridge_width 0.5)
				(island_removal_mode 0)
			)
			(polygon
				(pts
					(xy 83.928966 -63.881) (xy 83.928966 -65.913) (xy 85.325966 -65.913) (xy 85.325966 -67.437) (xy 85.833966 -67.437)
					(xy 85.833966 -65.913) (xy 87.230966 -65.913) (xy 87.230966 -63.881) (xy 85.833966 -63.881) (xy 85.833966 -62.357)
					(xy 85.325966 -62.357) (xy 85.325966 -63.881)
				)
			)
		)
	)
	(footprint ""
		(layer "F.Cu")
		(at 86.614 -29.09316 180)
		(property "Reference" "SR582"
			(at 0 0 180)
			(layer "F.SilkS")
			(hide yes)
			(effects
				(font
					(size 1.27 1.27)
				)
			)
		)
		(property "Value" "51R2F-2-GP"
			(at 0.064008 -3.993896 180)
			(unlocked yes)
			(layer "F.Fab")
			(hide yes)
			(effects
				(font
					(size 1.016 1.016)
					(thickness 0.1524)
				)
			)
		)
		(property "Device Type" "R402H16"
			(at 0.064008 -5.517896 180)
			(unlocked yes)
			(layer "F.Fab")
			(hide yes)
			(effects
				(font
					(size 1.016 1.016)
					(thickness 0.1524)
				)
			)
		)
		(duplicate_pad_numbers_are_jumpers no)
		(fp_line
			(start 0.508 -0.9398)
			(end -0.508 -0.9398)
			(stroke
				(width 0.1524)
				(type default)
			)
			(layer "F.SilkS")
		)
		(fp_line
			(start -0.508 -0.9398)
			(end -0.508 0.9398)
			(stroke
				(width 0.1524)
				(type default)
			)
			(layer "F.SilkS")
		)
		(fp_rect
			(start -0.508 0.9398)
			(end 0.508 -0.9398)
			(stroke
				(width 0)
				(type default)
			)
			(fill no)
			(layer "F.CrtYd")
		)
		(fp_rect
			(start -0.508 0.9398)
			(end 0.508 -0.9398)
			(stroke
				(width 0)
				(type default)
			)
			(fill no)
			(layer "F.Fab")
		)
		(pad "1" smd custom
			(at 0 -0.4445 180)
			(size 0.1397 0.1397)
			(layers "F.Cu" "F.Mask" "F.Paste")
			(net "CLK_100M_PCIE_P")
			(options
				(clearance outline)
				(anchor circle)
			)
			(primitives
				(gr_poly
					(pts
						(arc
							(start -0.1778 -0.2794)
							(mid -0.249642 -0.249642)
							(end -0.2794 -0.1778)
						)
						(arc
							(start -0.2794 0.1778)
							(mid -0.249642 0.249642)
							(end -0.1778 0.2794)
						)
						(arc
							(start 0.1778 0.2794)
							(mid 0.249642 0.249642)
							(end 0.2794 0.1778)
						)
						(arc
							(start 0.2794 -0.1778)
							(mid 0.249642 -0.249642)
							(end 0.1778 -0.2794)
						)
					)
					(width 0)
					(fill yes)
				)
			)
		)
		(pad "2" smd custom
			(at 0 0.4445 180)
			(size 0.1397 0.1397)
			(layers "F.Cu" "F.Mask" "F.Paste")
			(net "CK_100M_EXP_SAS")
			(options
				(clearance outline)
				(anchor circle)
			)
			(primitives
				(gr_poly
					(pts
						(arc
							(start -0.1778 -0.2794)
							(mid -0.249642 -0.249642)
							(end -0.2794 -0.1778)
						)
						(arc
							(start -0.2794 0.1778)
							(mid -0.249642 0.249642)
							(end -0.1778 0.2794)
						)
						(arc
							(start 0.1778 0.2794)
							(mid 0.249642 0.249642)
							(end 0.2794 0.1778)
						)
						(arc
							(start 0.2794 -0.1778)
							(mid 0.249642 -0.249642)
							(end 0.1778 -0.2794)
						)
					)
					(width 0)
					(fill yes)
				)
			)
		)
	)
	(footprint ""
		(layer "F.Cu")
		(at 73.827386 -109.392212 90)
		(property "Reference" "PQ3"
			(at 0 0 90)
			(layer "F.SilkS")
			(hide yes)
			(effects
				(font
					(size 1.27 1.27)
				)
			)
		)
		(property "Value" "FDN359BN-GP-U"
			(at -3.175 0.254 90)
			(unlocked yes)
			(layer "F.Fab")
			(hide yes)
			(effects
				(font
					(size 1.016 1.016)
					(thickness 0.1524)
				)
			)
		)
		(property "Device Type" "SOT23DGS2D6H45"
			(at -3.175 -1.27 90)
			(unlocked yes)
			(layer "F.Fab")
			(hide yes)
			(effects
				(font
					(size 1.016 1.016)
					(thickness 0.1524)
				)
			)
		)
		(duplicate_pad_numbers_are_jumpers no)
		(fp_line
			(start 1.7018 -1.905)
			(end 1.7018 1.905)
			(stroke
				(width 0.1524)
				(type default)
			)
			(layer "F.SilkS")
		)
		(fp_line
			(start -1.7018 -1.905)
			(end 1.7018 -1.905)
			(stroke
				(width 0.1524)
				(type default)
			)
			(layer "F.SilkS")
		)
		(fp_line
			(start 1.7018 1.905)
			(end -1.7018 1.905)
			(stroke
				(width 0.1524)
				(type default)
			)
			(layer "F.SilkS")
		)
		(fp_line
			(start -1.7018 1.905)
			(end -1.7018 -1.905)
			(stroke
				(width 0.1524)
				(type default)
			)
			(layer "F.SilkS")
		)
		(fp_rect
			(start -2.0066 1.9812)
			(end 2.0066 -1.9812)
			(stroke
				(width 0)
				(type default)
			)
			(fill no)
			(layer "F.CrtYd")
		)
		(fp_rect
			(start -2.0066 1.9812)
			(end 2.0066 -1.9812)
			(stroke
				(width 0)
				(type default)
			)
			(fill no)
			(layer "F.Fab")
		)
		(pad "D" smd custom
			(at 0 -1.0922 90)
			(size 0.1651 0.1651)
			(layers "F.Cu" "F.Mask" "F.Paste")
			(net "P1V8_STBY")
			(options
				(clearance outline)
				(anchor circle)
			)
			(primitives
				(gr_poly
					(pts
						(arc
							(start 0.3302 -0.381)
							(mid 0.270684 -0.524684)
							(end 0.127 -0.5842)
						)
						(arc
							(start -0.127 -0.5842)
							(mid -0.270684 -0.524684)
							(end -0.3302 -0.381)
						)
						(arc
							(start -0.3302 0.381)
							(mid -0.270684 0.524684)
							(end -0.127 0.5842)
						)
						(arc
							(start 0.127 0.5842)
							(mid 0.270684 0.524684)
							(end 0.3302 0.381)
						)
					)
					(width 0)
					(fill yes)
				)
			)
		)
		(pad "G" smd custom
			(at -0.94996 1.0922 90)
			(size 0.1651 0.1651)
			(layers "F.Cu" "F.Mask" "F.Paste")
			(net "P1V8_EN_LV")
			(options
				(clearance outline)
				(anchor circle)
			)
			(primitives
				(gr_poly
					(pts
						(arc
							(start 0.3302 -0.381)
							(mid 0.270684 -0.524684)
							(end 0.127 -0.5842)
						)
						(arc
							(start -0.127 -0.5842)
							(mid -0.270684 -0.524684)
							(end -0.3302 -0.381)
						)
						(arc
							(start -0.3302 0.381)
							(mid -0.270684 0.524684)
							(end -0.127 0.5842)
						)
						(arc
							(start 0.127 0.5842)
							(mid 0.270684 0.524684)
							(end 0.3302 0.381)
						)
					)
					(width 0)
					(fill yes)
				)
			)
		)
		(pad "S" smd custom
			(at 0.94996 1.0922 90)
			(size 0.1651 0.1651)
			(layers "F.Cu" "F.Mask" "F.Paste")
			(net "P1V8_E")
			(options
				(clearance outline)
				(anchor circle)
			)
			(primitives
				(gr_poly
					(pts
						(arc
							(start 0.3302 -0.381)
							(mid 0.270684 -0.524684)
							(end 0.127 -0.5842)
						)
						(arc
							(start -0.127 -0.5842)
							(mid -0.270684 -0.524684)
							(end -0.3302 -0.381)
						)
						(arc
							(start -0.3302 0.381)
							(mid -0.270684 0.524684)
							(end -0.127 0.5842)
						)
						(arc
							(start 0.127 0.5842)
							(mid 0.270684 0.524684)
							(end 0.3302 0.381)
						)
					)
					(width 0)
					(fill yes)
				)
			)
		)
	)
	(footprint ""
		(layer "F.Cu")
		(at 311.531 -194.945)
		(property "Reference" "TP172"
			(at 0 0 0)
			(layer "F.SilkS")
			(hide yes)
			(effects
				(font
					(size 1.27 1.27)
				)
			)
		)
		(property "Value" "TPAD28"
			(at -0.0127 -1.6637 0)
			(unlocked yes)
			(layer "F.Fab")
			(hide yes)
			(effects
				(font
					(size 1.016 1.016)
					(thickness 0.1524)
				)
			)
		)
		(property "Device Type" "TPAD28"
			(at -0.0127 -3.1877 0)
			(unlocked yes)
			(layer "F.Fab")
			(hide yes)
			(effects
				(font
					(size 1.016 1.016)
					(thickness 0.1524)
				)
			)
		)
		(duplicate_pad_numbers_are_jumpers no)
		(fp_poly
			(pts
				(arc
					(start 0.3556 0)
					(mid -0.3556 0)
					(end 0.3556 0)
				)
			)
			(stroke
				(width 0)
				(type default)
			)
			(fill no)
			(layer "F.CrtYd")
		)
		(fp_poly
			(pts
				(arc
					(start 0.6096 0)
					(mid -0.6096 0)
					(end 0.6096 0)
				)
			)
			(stroke
				(width 0)
				(type default)
			)
			(fill no)
			(layer "F.Fab")
		)
		(pad "1" smd circle
			(at 0 0)
			(size 0.7112 0.7112)
			(layers "F.Cu" "F.Mask" "F.Paste")
			(net "JTAG_BMC_TRST_N")
		)
	)
)
